(kicad_pcb
	(version 20241229)
	(generator "pcbnew")
	(generator_version "9.0")
	(general
		(thickness 1.552)
		(legacy_teardrops no)
	)
	(paper "A4")
	(title_block
		(date "2023-07-25")
		(rev "1.1.4")
		(comment 9 "footprints 12-13 of 379")
	)
	(layers
		(0 "F.Cu" signal)
		(4 "In1.Cu" signal)
		(6 "In2.Cu" signal)
		(8 "In3.Cu" signal)
		(10 "In4.Cu" signal)
		(12 "In5.Cu" signal)
		(14 "In6.Cu" signal)
		(2 "B.Cu" signal)
		(9 "F.Adhes" user "F.Adhesive")
		(11 "B.Adhes" user "B.Adhesive")
		(13 "F.Paste" user)
		(15 "B.Paste" user)
		(5 "F.SilkS" user "F.Silkscreen")
		(7 "B.SilkS" user "B.Silkscreen")
		(1 "F.Mask" user)
		(3 "B.Mask" user)
		(17 "Dwgs.User" user "User.Drawings")
		(19 "Cmts.User" user "User.Comments")
		(21 "Eco1.User" user "User.Eco1")
		(23 "Eco2.User" user "User.Eco2")
		(25 "Edge.Cuts" user)
		(27 "Margin" user)
		(31 "F.CrtYd" user "F.Courtyard")
		(29 "B.CrtYd" user "B.Courtyard")
		(35 "F.Fab" user)
		(33 "B.Fab" user)
	)
	(footprint "antmicro-footprints:USB-C_Receptacle_GCT_USB4105-GF-A"
		(layer "F.Cu")
		(at 154.03 59.002 180)
		(property "Reference" "J1"
			(at 0.45 -5.138 0)
			(layer "F.SilkS")
			(effects
				(font
					(size 0.65 0.65)
					(thickness 0.15)
				)
				(justify right bottom)
			)
		)
		(property "Value" "USB-C_USB4105-GF-A"
			(at 0 5 0)
			(layer "F.Fab")
			(hide yes)
			(effects
				(font
					(size 0.7 0.7)
					(thickness 0.15)
				)
				(justify right bottom)
			)
		)
		(property "Datasheet" "https://gct.co/files/drawings/usb4105.pdf"
			(at 0 0 180)
			(layer "F.Fab")
			(hide yes)
			(effects
				(font
					(size 1.27 1.27)
					(thickness 0.15)
				)
			)
		)
		(property "Description" "USB-C (USB TYPE-C) USB 2.0 Receptacle Connector 24 (16+8 Dummy) Position Surface Mount, Right Angle"
			(at 0 0 180)
			(layer "F.Fab")
			(hide yes)
			(effects
				(font
					(size 1.27 1.27)
					(thickness 0.15)
				)
			)
		)
		(property "Author" "Antmicro"
			(at 308.06 118.004 0)
			(layer "F.Fab")
			(hide yes)
			(effects
				(font
					(size 1 1)
					(thickness 0.15)
				)
			)
		)
		(property "License" "Apache-2.0"
			(at 308.06 118.004 0)
			(layer "F.Fab")
			(hide yes)
			(effects
				(font
					(size 1 1)
					(thickness 0.15)
				)
			)
		)
		(property "MPN" "USB4105-GF-A"
			(at 308.06 118.004 0)
			(layer "F.Fab")
			(hide yes)
			(effects
				(font
					(size 1 1)
					(thickness 0.15)
				)
			)
		)
		(property "Manufacturer" "GCT"
			(at 308.06 118.004 0)
			(layer "F.Fab")
			(hide yes)
			(effects
				(font
					(size 1 1)
					(thickness 0.15)
				)
			)
		)
		(sheetname "/Peripherals/")
		(sheetfile "peripherals.kicad_sch")
		(attr smd)
		(fp_line
			(start 4.788 3.854)
			(end 4.788 2.575)
			(stroke
				(width 0.15)
				(type solid)
			)
			(layer "F.SilkS")
		)
		(fp_line
			(start 4.788 -1.395)
			(end 4.788 -0.145)
			(stroke
				(width 0.15)
				(type solid)
			)
			(layer "F.SilkS")
		)
		(fp_line
			(start -4.79 3.854)
			(end 4.788 3.854)
			(stroke
				(width 0.15)
				(type solid)
			)
			(layer "F.SilkS")
		)
		(fp_line
			(start -4.79 2.575)
			(end -4.79 3.854)
			(stroke
				(width 0.15)
				(type solid)
			)
			(layer "F.SilkS")
		)
		(fp_line
			(start -4.79 -1.395)
			(end -4.79 -0.145)
			(stroke
				(width 0.15)
				(type solid)
			)
			(layer "F.SilkS")
		)
		(fp_circle
			(center -3.8 -4.27071)
			(end -3.75 -4.22071)
			(stroke
				(width 0.15)
				(type solid)
			)
			(fill yes)
			(layer "F.SilkS")
		)
		(fp_rect
			(start -5.1 -4.4)
			(end 5.1 3.9)
			(stroke
				(width 0.05)
				(type solid)
			)
			(fill no)
			(layer "F.CrtYd")
		)
		(fp_line
			(start 4.788 3.854)
			(end -4.79 3.854)
			(stroke
				(width 0.15)
				(type solid)
			)
			(layer "F.Fab")
		)
		(fp_line
			(start 4.788 -3.676)
			(end 4.788 3.854)
			(stroke
				(width 0.15)
				(type solid)
			)
			(layer "F.Fab")
		)
		(fp_line
			(start -4.702 3.854)
			(end 4.788 3.854)
			(stroke
				(width 0.15)
				(type solid)
			)
			(layer "F.Fab")
		)
		(fp_line
			(start -4.79 3.854)
			(end -4.79 -3.676)
			(stroke
				(width 0.15)
				(type solid)
			)
			(layer "F.Fab")
		)
		(fp_line
			(start -4.79 -3.676)
			(end 4.788 -3.676)
			(stroke
				(width 0.15)
				(type solid)
			)
			(layer "F.Fab")
		)
		(fp_text user "License: Apache-2.0"
			(at -4.79 8.855 180)
			(layer "F.Fab")
			(effects
				(font
					(size 0.7 0.7)
					(thickness 0.15)
				)
				(justify left bottom)
			)
		)
		(fp_text user "Author: Antmicro"
			(at -4.79 7.853 180)
			(layer "F.Fab")
			(effects
				(font
					(size 0.7 0.7)
					(thickness 0.15)
				)
				(justify left bottom)
			)
		)
		(fp_text user "${REFERENCE}"
			(at -4.79 6.853 180)
			(layer "F.Fab")
			(effects
				(font
					(size 0.7 0.7)
					(thickness 0.15)
				)
				(justify left bottom)
			)
		)
		(fp_text user "PCB-EDGE"
			(at -4.79 5.853 180)
			(layer "F.Fab")
			(effects
				(font
					(size 0.7 0.7)
					(thickness 0.15)
				)
				(justify left bottom)
			)
		)
		(pad "" np_thru_hole circle
			(at -2.891 -2.426 180)
			(size 0.65 0.65)
			(drill 0.65)
			(layers "*.Cu" "*.Mask")
		)
		(pad "" np_thru_hole circle
			(at 2.89 -2.426 180)
			(size 0.65 0.65)
			(drill 0.65)
			(layers "*.Cu" "*.Mask")
		)
		(pad "A1" smd roundrect
			(at -3.202 -3.5 180)
			(size 0.6 1.15)
			(layers "F.Cu" "F.Mask" "F.Paste")
			(roundrect_rratio 0.25)
			(net 1 "GND")
			(pinfunction "GND")
			(pintype "power_in")
		)
		(pad "A4" smd roundrect
			(at -2.4 -3.5 180)
			(size 0.6 1.15)
			(layers "F.Cu" "F.Mask" "F.Paste")
			(roundrect_rratio 0.25)
			(net 325 "USB_POWER_IN")
			(pinfunction "VBUS")
			(pintype "power_in")
		)
		(pad "A5" smd roundrect
			(at -1.25 -3.5 180)
			(size 0.3 1.15)
			(layers "F.Cu" "F.Mask" "F.Paste")
			(roundrect_rratio 0.25)
			(net 311 "Net-(J1-CC_{1})")
			(pinfunction "CC_{1}")
			(pintype "bidirectional")
		)
		(pad "A6" smd roundrect
			(at -0.25 -3.5 180)
			(size 0.3 1.15)
			(layers "F.Cu" "F.Mask" "F.Paste")
			(roundrect_rratio 0.25)
			(net 359 "/Peripherals/USB_DP")
			(pinfunction "D_{A}+")
			(pintype "bidirectional")
		)
		(pad "A7" smd roundrect
			(at 0.248 -3.5 180)
			(size 0.3 1.15)
			(layers "F.Cu" "F.Mask" "F.Paste")
			(roundrect_rratio 0.25)
			(net 360 "/Peripherals/USB_DN")
			(pinfunction "D_{A}-")
			(pintype "bidirectional")
		)
		(pad "A8" smd roundrect
			(at 1.249 -3.5 180)
			(size 0.3 1.15)
			(layers "F.Cu" "F.Mask" "F.Paste")
			(roundrect_rratio 0.25)
			(net 297 "unconnected-(J1-SBU_{1}-PadA8)")
			(pinfunction "SBU_{1}")
			(pintype "bidirectional+no_connect")
		)
		(pad "A9" smd roundrect
			(at 2.398 -3.5 180)
			(size 0.6 1.15)
			(layers "F.Cu" "F.Mask" "F.Paste")
			(roundrect_rratio 0.25)
			(net 325 "USB_POWER_IN")
			(pinfunction "VBUS")
			(pintype "passive")
		)
		(pad "A12" smd roundrect
			(at 3.2 -3.5 180)
			(size 0.6 1.15)
			(layers "F.Cu" "F.Mask" "F.Paste")
			(roundrect_rratio 0.25)
			(net 1 "GND")
			(pinfunction "GND")
			(pintype "passive")
		)
		(pad "B1" smd roundrect
			(at 3.2 -3.5 180)
			(size 0.6 1.15)
			(layers "F.Cu" "F.Mask" "F.Paste")
			(roundrect_rratio 0.25)
			(net 1 "GND")
			(pinfunction "GND")
			(pintype "passive")
		)
		(pad "B4" smd roundrect
			(at 2.398 -3.5 180)
			(size 0.6 1.15)
			(layers "F.Cu" "F.Mask" "F.Paste")
			(roundrect_rratio 0.25)
			(net 325 "USB_POWER_IN")
			(pinfunction "VBUS")
			(pintype "passive")
		)
		(pad "B5" smd roundrect
			(at 1.749 -3.5 180)
			(size 0.3 1.15)
			(layers "F.Cu" "F.Mask" "F.Paste")
			(roundrect_rratio 0.25)
			(net 350 "Net-(J1-CC_{2})")
			(pinfunction "CC_{2}")
			(pintype "bidirectional")
		)
		(pad "B6" smd roundrect
			(at 0.748 -3.5 180)
			(size 0.3 1.15)
			(layers "F.Cu" "F.Mask" "F.Paste")
			(roundrect_rratio 0.25)
			(net 359 "/Peripherals/USB_DP")
			(pinfunction "D_{B}+")
			(pintype "bidirectional")
		)
		(pad "B7" smd roundrect
			(at -0.75 -3.5 180)
			(size 0.3 1.15)
			(layers "F.Cu" "F.Mask" "F.Paste")
			(roundrect_rratio 0.25)
			(net 360 "/Peripherals/USB_DN")
			(pinfunction "D_{B}-")
			(pintype "bidirectional")
		)
		(pad "B8" smd roundrect
			(at -1.75 -3.5 180)
			(size 0.3 1.15)
			(layers "F.Cu" "F.Mask" "F.Paste")
			(roundrect_rratio 0.25)
			(net 352 "unconnected-(J1-SBU_{2}-PadB8)")
			(pinfunction "SBU_{2}")
			(pintype "bidirectional+no_connect")
		)
		(pad "B9" smd roundrect
			(at -2.4 -3.5 180)
			(size 0.6 1.15)
			(layers "F.Cu" "F.Mask" "F.Paste")
			(roundrect_rratio 0.25)
			(net 325 "USB_POWER_IN")
			(pinfunction "VBUS")
			(pintype "passive")
		)
		(pad "B12" smd roundrect
			(at -3.202 -3.5 180)
			(size 0.6 1.15)
			(layers "F.Cu" "F.Mask" "F.Paste")
			(roundrect_rratio 0.25)
			(net 1 "GND")
			(pinfunction "GND")
			(pintype "passive")
		)
		(pad "SH" thru_hole oval
			(at -4.321 -2.926 180)
			(size 1.05 2.1)
			(drill oval 0.6 1.7)
			(layers "*.Cu" "*.Mask")
			(remove_unused_layers no)
			(net 1 "GND")
			(pinfunction "SH")
			(pintype "passive")
		)
		(pad "SH" thru_hole oval
			(at -4.321 1.255 180)
			(size 1 2)
			(drill oval 0.6 1.4)
			(layers "*.Cu" "*.Mask")
			(remove_unused_layers no)
			(net 1 "GND")
			(pinfunction "SH")
			(pintype "passive")
		)
		(pad "SH" thru_hole oval
			(at 4.32 -2.926 180)
			(size 1.05 2.1)
			(drill oval 0.6 1.7)
			(layers "*.Cu" "*.Mask")
			(remove_unused_layers no)
			(net 1 "GND")
			(pinfunction "SH")
			(pintype "passive")
		)
		(pad "SH" thru_hole oval
			(at 4.32 1.255 180)
			(size 1 2)
			(drill oval 0.6 1.4)
			(layers "*.Cu" "*.Mask")
			(remove_unused_layers no)
			(net 1 "GND")
			(pinfunction "SH")
			(pintype "passive")
		)
	)
	(footprint "antmicro-footprints:C_0402_1005Metric"
		(layer "F.Cu")
		(at 100.97 86.46 90)
		(descr "Capacitor SMD 0402")
		(tags "capacitor SMD 0402")
		(property "Reference" "C51"
			(at -3.08 0.36 90)
			(layer "F.SilkS")
			(effects
				(font
					(size 0.65 0.65)
					(thickness 0.15)
				)
				(justify left bottom)
			)
		)
		(property "Value" "C_33p_0402"
			(at 0 1.4 90)
			(layer "F.Fab")
			(hide yes)
			(effects
				(font
					(size 0.7 0.7)
					(thickness 0.15)
				)
				(justify left bottom)
			)
		)
		(property "Datasheet" "https://spicat.kyocera-avx.com/product/mlcc/chartview/04025A330FAT2A/"
			(at 0 0 90)
			(layer "F.Fab")
			(hide yes)
			(effects
				(font
					(size 1.27 1.27)
					(thickness 0.15)
				)
			)
		)
		(property "Description" "SMD Multilayer Ceramic Capacitor, 33 pF, 50 V, 0402 [1005 Metric], ± 5%, C0G / NP0, MC"
			(at 0 0 90)
			(layer "F.Fab")
			(hide yes)
			(effects
				(font
					(size 1.27 1.27)
					(thickness 0.15)
				)
			)
		)
		(property "Author" "Antmicro"
			(at 187.43 -14.51 0)
			(layer "F.Fab")
			(hide yes)
			(effects
				(font
					(size 1 1)
					(thickness 0.15)
				)
			)
		)
		(property "Dielectric" ""
			(at 187.43 -14.51 0)
			(layer "F.Fab")
			(hide yes)
			(effects
				(font
					(size 1 1)
					(thickness 0.15)
				)
			)
		)
		(property "License" "Apache-2.0"
			(at 187.43 -14.51 0)
			(layer "F.Fab")
			(hide yes)
			(effects
				(font
					(size 1 1)
					(thickness 0.15)
				)
			)
		)
		(property "MPN" "04025A330FAT2A"
			(at 187.43 -14.51 0)
			(layer "F.Fab")
			(hide yes)
			(effects
				(font
					(size 1 1)
					(thickness 0.15)
				)
			)
		)
		(property "Manufacturer" "KYOCERA AVX"
			(at 187.43 -14.51 0)
			(layer "F.Fab")
			(hide yes)
			(effects
				(font
					(size 1 1)
					(thickness 0.15)
				)
			)
		)
		(property "Val" "33p"
			(at 187.43 -14.51 0)
			(layer "F.Fab")
			(hide yes)
			(effects
				(font
					(size 1 1)
					(thickness 0.15)
				)
			)
		)
		(property "Voltage" ""
			(at 187.43 -14.51 0)
			(layer "F.Fab")
			(hide yes)
			(effects
				(font
					(size 1 1)
					(thickness 0.15)
				)
			)
		)
		(sheetname "/SDI/")
		(sheetfile "sdi.kicad_sch")
		(attr smd)
		(fp_rect
			(start -0.925 -0.47)
			(end 0.925 0.47)
			(stroke
				(width 0.05)
				(type default)
			)
			(fill no)
			(layer "F.CrtYd")
		)
		(fp_line
			(start 0.504 -0.25)
			(end 0.504 0.248)
			(stroke
				(width 0.15)
				(type solid)
			)
			(layer "F.Fab")
		)
		(fp_line
			(start -0.494 -0.25)
			(end 0.504 -0.25)
			(stroke
				(width 0.15)
				(type solid)
			)
			(layer "F.Fab")
		)
		(fp_line
			(start 0.504 0.248)
			(end -0.494 0.248)
			(stroke
				(width 0.15)
				(type solid)
			)
			(layer "F.Fab")
		)
		(fp_line
			(start -0.494 0.248)
			(end -0.494 -0.25)
			(stroke
				(width 0.15)
				(type solid)
			)
			(layer "F.Fab")
		)
		(fp_text user "License: Apache-2.0"
			(at -0.939 5.799 90)
			(layer "F.Fab")
			(effects
				(font
					(size 0.7 0.7)
					(thickness 0.15)
				)
				(justify left bottom)
			)
		)
		(fp_text user "${REFERENCE}"
			(at -0.939 4.599 90)
			(layer "F.Fab")
			(effects
				(font
					(size 0.7 0.7)
					(thickness 0.15)
				)
				(justify left bottom)
			)
		)
		(fp_text user "Author: Antmicro"
			(at -0.939 3.399 90)
			(layer "F.Fab")
			(effects
				(font
					(size 0.7 0.7)
					(thickness 0.15)
				)
				(justify left bottom)
			)
		)
		(pad "1" smd roundrect
			(at -0.48 0 90)
			(size 0.59 0.64)
			(layers "F.Cu" "F.Mask" "F.Paste")
			(roundrect_rratio 0.25)
			(net 46 "/SDI/XTAL2")
			(pintype "passive")
		)
		(pad "2" smd roundrect
			(at 0.48 0 90)
			(size 0.59 0.64)
			(layers "F.Cu" "F.Mask" "F.Paste")
			(roundrect_rratio 0.25)
			(net 1 "GND")
			(pintype "passive")
		)
	)
)
